(kicad_pcb
	(version 20260206)
	(generator "pcbnew")
	(generator_version "10.0")
	(general
		(thickness 1.6)
		(legacy_teardrops no)
	)
	(paper "A4")
	(title_block
		(title "baseboard — 13948-1b.1110WZS1818.brd")
		(comment 1 "Honey Badger (Wiwynn) / footprints 1029-1035 of 2523")
	)
	(layers
		(0 "F.Cu" signal "TOP")
		(4 "In1.Cu" signal "L2GND")
		(6 "In2.Cu" signal "L3")
		(8 "In3.Cu" signal "L4VCC")
		(10 "In4.Cu" signal "L5VCC")
		(12 "In5.Cu" signal "L6")
		(14 "In6.Cu" signal "L7GND")
		(2 "B.Cu" signal "BOTTOM")
		(9 "F.Adhes" user "F.Adhesive")
		(11 "B.Adhes" user "B.Adhesive")
		(13 "F.Paste" user "Package Geometry/Pastemask Top")
		(15 "B.Paste" user "Package Geometry/Pastemask Bottom")
		(5 "F.SilkS" user "Ref Des/Silkscreen Top")
		(7 "B.SilkS" user "Ref Des/Silkscreen Bottom")
		(1 "F.Mask" user "Board Geometry/Soldermask Top")
		(3 "B.Mask" user "Board Geometry/Soldermask Bottom")
		(17 "Dwgs.User" user "User.Drawings")
		(19 "Cmts.User" user "User.Comments")
		(21 "Eco1.User" user "User.Eco1")
		(23 "Eco2.User" user "User.Eco2")
		(25 "Edge.Cuts" user "Board Geometry/Outline")
		(27 "Margin" user)
		(31 "F.CrtYd" user "Package Geometry/Place Bound Top")
		(29 "B.CrtYd" user "Package Geometry/Place Bound Bottom")
		(35 "F.Fab" user "Ref Des/Assembly Top")
		(33 "B.Fab" user "Ref Des/Assembly Bottom")
	)
	(footprint ""
		(layer "F.Cu")
		(at 273.158966 -18.734532 -90)
		(property "Reference" "C240"
			(at 0 0 270)
			(layer "F.SilkS")
			(hide yes)
			(effects
				(font
					(size 1.27 1.27)
				)
			)
		)
		(property "Value" "SCD1U16V2JX-1-GP"
			(at 1.1811 -2.7051 270)
			(unlocked yes)
			(layer "F.Fab")
			(hide yes)
			(effects
				(font
					(size 1.016 1.016)
					(thickness 0.1524)
				)
			)
		)
		(property "Device Type" "C402H22"
			(at 1.1811 -4.2291 270)
			(unlocked yes)
			(layer "F.Fab")
			(hide yes)
			(effects
				(font
					(size 1.016 1.016)
					(thickness 0.1524)
				)
			)
		)
		(duplicate_pad_numbers_are_jumpers no)
		(fp_rect
			(start -0.4318 0.9525)
			(end 0.4318 -0.9525)
			(stroke
				(width 0)
				(type default)
			)
			(fill no)
			(layer "F.CrtYd")
		)
		(fp_rect
			(start -0.4318 0.9525)
			(end 0.4318 -0.9525)
			(stroke
				(width 0)
				(type default)
			)
			(fill no)
			(layer "F.Fab")
		)
		(pad "1" smd custom
			(at 0 -0.4445 270)
			(size 0.1524 0.1524)
			(layers "F.Cu" "F.Mask" "F.Paste")
			(net "P5V_USB")
			(options
				(clearance outline)
				(anchor circle)
			)
			(primitives
				(gr_poly
					(pts
						(arc
							(start 0.3048 -0.2032)
							(mid 0.275042 -0.275042)
							(end 0.2032 -0.3048)
						)
						(arc
							(start -0.2032 -0.3048)
							(mid -0.275042 -0.275042)
							(end -0.3048 -0.2032)
						)
						(arc
							(start -0.3048 0.2032)
							(mid -0.275042 0.275042)
							(end -0.2032 0.3048)
						)
						(arc
							(start 0.2032 0.3048)
							(mid 0.275042 0.275042)
							(end 0.3048 0.2032)
						)
					)
					(width 0)
					(fill yes)
				)
			)
		)
		(pad "2" smd custom
			(at 0 0.4445 270)
			(size 0.1524 0.1524)
			(layers "F.Cu" "F.Mask" "F.Paste")
			(net "GND")
			(options
				(clearance outline)
				(anchor circle)
			)
			(primitives
				(gr_poly
					(pts
						(arc
							(start 0.3048 -0.2032)
							(mid 0.275042 -0.275042)
							(end 0.2032 -0.3048)
						)
						(arc
							(start -0.2032 -0.3048)
							(mid -0.275042 -0.275042)
							(end -0.3048 -0.2032)
						)
						(arc
							(start -0.3048 0.2032)
							(mid -0.275042 0.275042)
							(end -0.2032 0.3048)
						)
						(arc
							(start 0.2032 0.3048)
							(mid 0.275042 0.275042)
							(end 0.3048 0.2032)
						)
					)
					(width 0)
					(fill yes)
				)
			)
		)
	)
	(footprint ""
		(layer "F.Cu")
		(at 212.86597 -69.088)
		(property "Reference" "R17"
			(at 0 0 0)
			(layer "F.SilkS")
			(hide yes)
			(effects
				(font
					(size 1.27 1.27)
				)
			)
		)
		(property "Value" "100R2F-L1-GP-U"
			(at 0.064008 -3.993896 0)
			(unlocked yes)
			(layer "F.Fab")
			(hide yes)
			(effects
				(font
					(size 1.016 1.016)
					(thickness 0.1524)
				)
			)
		)
		(property "Device Type" "R402H14"
			(at 0.064008 -5.517896 0)
			(unlocked yes)
			(layer "F.Fab")
			(hide yes)
			(effects
				(font
					(size 1.016 1.016)
					(thickness 0.1524)
				)
			)
		)
		(duplicate_pad_numbers_are_jumpers no)
		(fp_line
			(start -0.508 -0.9398)
			(end -0.508 0.9398)
			(stroke
				(width 0.1524)
				(type default)
			)
			(layer "F.SilkS")
		)
		(fp_line
			(start 0.508 -0.9398)
			(end -0.508 -0.9398)
			(stroke
				(width 0.1524)
				(type default)
			)
			(layer "F.SilkS")
		)
		(fp_rect
			(start -0.508 0.9398)
			(end 0.508 -0.9398)
			(stroke
				(width 0)
				(type default)
			)
			(fill no)
			(layer "F.CrtYd")
		)
		(fp_rect
			(start -0.508 0.9398)
			(end 0.508 -0.9398)
			(stroke
				(width 0)
				(type default)
			)
			(fill no)
			(layer "F.Fab")
		)
		(pad "1" smd custom
			(at 0 -0.4445)
			(size 0.1397 0.1397)
			(layers "F.Cu" "F.Mask" "F.Paste")
			(net "SVR_ID2")
			(options
				(clearance outline)
				(anchor circle)
			)
			(primitives
				(gr_poly
					(pts
						(arc
							(start -0.1778 -0.2794)
							(mid -0.249642 -0.249642)
							(end -0.2794 -0.1778)
						)
						(arc
							(start -0.2794 0.1778)
							(mid -0.249642 0.249642)
							(end -0.1778 0.2794)
						)
						(arc
							(start 0.1778 0.2794)
							(mid 0.249642 0.249642)
							(end 0.2794 0.1778)
						)
						(arc
							(start 0.2794 -0.1778)
							(mid 0.249642 -0.249642)
							(end 0.1778 -0.2794)
						)
					)
					(width 0)
					(fill yes)
				)
			)
		)
		(pad "2" smd custom
			(at 0 0.4445)
			(size 0.1397 0.1397)
			(layers "F.Cu" "F.Mask" "F.Paste")
			(net "GND")
			(options
				(clearance outline)
				(anchor circle)
			)
			(primitives
				(gr_poly
					(pts
						(arc
							(start -0.1778 -0.2794)
							(mid -0.249642 -0.249642)
							(end -0.2794 -0.1778)
						)
						(arc
							(start -0.2794 0.1778)
							(mid -0.249642 0.249642)
							(end -0.1778 0.2794)
						)
						(arc
							(start 0.1778 0.2794)
							(mid 0.249642 0.249642)
							(end 0.2794 0.1778)
						)
						(arc
							(start 0.2794 -0.1778)
							(mid 0.249642 -0.249642)
							(end 0.1778 -0.2794)
						)
					)
					(width 0)
					(fill yes)
				)
			)
		)
	)
	(footprint ""
		(layer "F.Cu")
		(at 218.948 -168.275 -90)
		(property "Reference" "U178"
			(at 0 0 270)
			(layer "F.SilkS")
			(hide yes)
			(effects
				(font
					(size 1.27 1.27)
				)
			)
		)
		(property "Value" "SNLVC1G126DCKR-GP"
			(at -2.3368 -8.6868 270)
			(unlocked yes)
			(layer "F.Fab")
			(hide yes)
			(effects
				(font
					(size 1.016 1.016)
					(thickness 0.1524)
				)
			)
		)
		(property "Device Type" "SC70-5H44"
			(at -2.3114 -10.414 270)
			(unlocked yes)
			(layer "F.Fab")
			(hide yes)
			(effects
				(font
					(size 1.016 1.016)
					(thickness 0.1524)
				)
			)
		)
		(duplicate_pad_numbers_are_jumpers no)
		(fp_line
			(start -1.27 1.7018)
			(end -1.27 -1.7018)
			(stroke
				(width 0.1524)
				(type default)
			)
			(layer "F.SilkS")
		)
		(fp_line
			(start 1.27 1.7018)
			(end -1.27 1.7018)
			(stroke
				(width 0.1524)
				(type default)
			)
			(layer "F.SilkS")
		)
		(fp_line
			(start -1.27 -1.7018)
			(end 1.27 -1.7018)
			(stroke
				(width 0.1524)
				(type default)
			)
			(layer "F.SilkS")
		)
		(fp_line
			(start 1.27 -1.7018)
			(end 1.27 1.7018)
			(stroke
				(width 0.1524)
				(type default)
			)
			(layer "F.SilkS")
		)
		(fp_line
			(start 0.6604 -1.8034)
			(end 1.3843 -1.8034)
			(stroke
				(width 0.3302)
				(type default)
			)
			(layer "F.SilkS")
		)
		(fp_line
			(start 1.3843 -1.8034)
			(end 1.3843 -1.1176)
			(stroke
				(width 0.3302)
				(type default)
			)
			(layer "F.SilkS")
		)
		(fp_rect
			(start -1.524 1.9558)
			(end 1.524 -1.9558)
			(stroke
				(width 0)
				(type default)
			)
			(fill no)
			(layer "F.CrtYd")
		)
		(fp_poly
			(pts
				(xy -1.524 -1.9558) (xy 1.524 -1.9558) (xy 1.524 1.9558) (xy -1.524 1.9558)
			)
			(stroke
				(width 0)
				(type default)
			)
			(fill no)
			(layer "F.Fab")
		)
		(pad "1" smd rect
			(at 0.65024 -0.8255 270)
			(size 0.4064 1.2192)
			(layers "F.Cu" "F.Mask" "F.Paste")
			(net "JTAG_DT")
		)
		(pad "2" smd rect
			(at 0 -0.8255 270)
			(size 0.4064 1.2192)
			(layers "F.Cu" "F.Mask" "F.Paste")
			(net "JTAG_IOC_TDO_L")
		)
		(pad "3" smd rect
			(at -0.65024 -0.8255 270)
			(size 0.4064 1.2192)
			(layers "F.Cu" "F.Mask" "F.Paste")
			(net "GND")
		)
		(pad "4" smd rect
			(at -0.65024 0.8255 270)
			(size 0.4064 1.2192)
			(layers "F.Cu" "F.Mask" "F.Paste")
			(net "JTAG_BMC_TDI")
		)
		(pad "5" smd rect
			(at 0.65024 0.8255 270)
			(size 0.4064 1.2192)
			(layers "F.Cu" "F.Mask" "F.Paste")
			(net "P3V3_STBY")
		)
	)
	(footprint ""
		(layer "F.Cu")
		(at 301.752 -92.329 -90)
		(property "Reference" "R5309"
			(at 0 0 270)
			(layer "F.SilkS")
			(hide yes)
			(effects
				(font
					(size 1.27 1.27)
				)
			)
		)
		(property "Value" "0R2J-2-GP"
			(at 0.064008 -3.993896 270)
			(unlocked yes)
			(layer "F.Fab")
			(hide yes)
			(effects
				(font
					(size 1.016 1.016)
					(thickness 0.1524)
				)
			)
		)
		(property "Device Type" "R402H16"
			(at 0.064008 -5.517896 270)
			(unlocked yes)
			(layer "F.Fab")
			(hide yes)
			(effects
				(font
					(size 1.016 1.016)
					(thickness 0.1524)
				)
			)
		)
		(duplicate_pad_numbers_are_jumpers no)
		(fp_line
			(start -0.508 -0.9398)
			(end -0.508 0.9398)
			(stroke
				(width 0.1524)
				(type default)
			)
			(layer "F.SilkS")
		)
		(fp_line
			(start 0.508 -0.9398)
			(end -0.508 -0.9398)
			(stroke
				(width 0.1524)
				(type default)
			)
			(layer "F.SilkS")
		)
		(fp_rect
			(start -0.508 0.9398)
			(end 0.508 -0.9398)
			(stroke
				(width 0)
				(type default)
			)
			(fill no)
			(layer "F.CrtYd")
		)
		(fp_rect
			(start -0.508 0.9398)
			(end 0.508 -0.9398)
			(stroke
				(width 0)
				(type default)
			)
			(fill no)
			(layer "F.Fab")
		)
		(pad "1" smd custom
			(at 0 -0.4445 270)
			(size 0.1397 0.1397)
			(layers "F.Cu" "F.Mask" "F.Paste")
			(net "BMC_I2C_SCL_10")
			(options
				(clearance outline)
				(anchor circle)
			)
			(primitives
				(gr_poly
					(pts
						(arc
							(start -0.1778 -0.2794)
							(mid -0.249642 -0.249642)
							(end -0.2794 -0.1778)
						)
						(arc
							(start -0.2794 0.1778)
							(mid -0.249642 0.249642)
							(end -0.1778 0.2794)
						)
						(arc
							(start 0.1778 0.2794)
							(mid 0.249642 0.249642)
							(end 0.2794 0.1778)
						)
						(arc
							(start 0.2794 -0.1778)
							(mid 0.249642 -0.249642)
							(end 0.1778 -0.2794)
						)
					)
					(width 0)
					(fill yes)
				)
			)
		)
		(pad "2" smd custom
			(at 0 0.4445 270)
			(size 0.1397 0.1397)
			(layers "F.Cu" "F.Mask" "F.Paste")
			(net "TEMP_2_SCL")
			(options
				(clearance outline)
				(anchor circle)
			)
			(primitives
				(gr_poly
					(pts
						(arc
							(start -0.1778 -0.2794)
							(mid -0.249642 -0.249642)
							(end -0.2794 -0.1778)
						)
						(arc
							(start -0.2794 0.1778)
							(mid -0.249642 0.249642)
							(end -0.1778 0.2794)
						)
						(arc
							(start 0.1778 0.2794)
							(mid 0.249642 0.249642)
							(end 0.2794 0.1778)
						)
						(arc
							(start 0.2794 -0.1778)
							(mid 0.249642 -0.249642)
							(end 0.1778 -0.2794)
						)
					)
					(width 0)
					(fill yes)
				)
			)
		)
	)
	(footprint ""
		(layer "F.Cu")
		(at 25.596088 -195.454016 180)
		(property "Reference" "SC546"
			(at 0 0 180)
			(layer "F.SilkS")
			(hide yes)
			(effects
				(font
					(size 1.27 1.27)
				)
			)
		)
		(property "Value" "SCD1U16V2KX-3GP"
			(at 1.1811 -2.7051 180)
			(unlocked yes)
			(layer "F.Fab")
			(hide yes)
			(effects
				(font
					(size 1.016 1.016)
					(thickness 0.1524)
				)
			)
		)
		(property "Device Type" "C402H22"
			(at 1.1811 -4.2291 180)
			(unlocked yes)
			(layer "F.Fab")
			(hide yes)
			(effects
				(font
					(size 1.016 1.016)
					(thickness 0.1524)
				)
			)
		)
		(duplicate_pad_numbers_are_jumpers no)
		(fp_rect
			(start -0.4318 0.9525)
			(end 0.4318 -0.9525)
			(stroke
				(width 0)
				(type default)
			)
			(fill no)
			(layer "F.CrtYd")
		)
		(fp_rect
			(start -0.4318 0.9525)
			(end 0.4318 -0.9525)
			(stroke
				(width 0)
				(type default)
			)
			(fill no)
			(layer "F.Fab")
		)
		(pad "1" smd custom
			(at 0 -0.4445 180)
			(size 0.1524 0.1524)
			(layers "F.Cu" "F.Mask" "F.Paste")
			(net "P1V8_E")
			(options
				(clearance outline)
				(anchor circle)
			)
			(primitives
				(gr_poly
					(pts
						(arc
							(start 0.3048 -0.2032)
							(mid 0.275042 -0.275042)
							(end 0.2032 -0.3048)
						)
						(arc
							(start -0.2032 -0.3048)
							(mid -0.275042 -0.275042)
							(end -0.3048 -0.2032)
						)
						(arc
							(start -0.3048 0.2032)
							(mid -0.275042 0.275042)
							(end -0.2032 0.3048)
						)
						(arc
							(start 0.2032 0.3048)
							(mid 0.275042 0.275042)
							(end 0.3048 0.2032)
						)
					)
					(width 0)
					(fill yes)
				)
			)
		)
		(pad "2" smd custom
			(at 0 0.4445 180)
			(size 0.1524 0.1524)
			(layers "F.Cu" "F.Mask" "F.Paste")
			(net "GND")
			(options
				(clearance outline)
				(anchor circle)
			)
			(primitives
				(gr_poly
					(pts
						(arc
							(start 0.3048 -0.2032)
							(mid 0.275042 -0.275042)
							(end 0.2032 -0.3048)
						)
						(arc
							(start -0.2032 -0.3048)
							(mid -0.275042 -0.275042)
							(end -0.3048 -0.2032)
						)
						(arc
							(start -0.3048 0.2032)
							(mid -0.275042 0.275042)
							(end -0.2032 0.3048)
						)
						(arc
							(start 0.2032 0.3048)
							(mid 0.275042 0.275042)
							(end 0.3048 0.2032)
						)
					)
					(width 0)
					(fill yes)
				)
			)
		)
	)
	(footprint ""
		(layer "F.Cu")
		(at 81.285842 -122.880882 -90)
		(property "Reference" "SC1106"
			(at 0 0 270)
			(layer "F.SilkS")
			(hide yes)
			(effects
				(font
					(size 1.27 1.27)
				)
			)
		)
		(property "Value" "SCD1U16V2KX-3GP"
			(at 1.1811 -2.7051 270)
			(unlocked yes)
			(layer "F.Fab")
			(hide yes)
			(effects
				(font
					(size 1.016 1.016)
					(thickness 0.1524)
				)
			)
		)
		(property "Device Type" "C402H22"
			(at 1.1811 -4.2291 270)
			(unlocked yes)
			(layer "F.Fab")
			(hide yes)
			(effects
				(font
					(size 1.016 1.016)
					(thickness 0.1524)
				)
			)
		)
		(duplicate_pad_numbers_are_jumpers no)
		(fp_rect
			(start -0.4318 0.9525)
			(end 0.4318 -0.9525)
			(stroke
				(width 0)
				(type default)
			)
			(fill no)
			(layer "F.CrtYd")
		)
		(fp_rect
			(start -0.4318 0.9525)
			(end 0.4318 -0.9525)
			(stroke
				(width 0)
				(type default)
			)
			(fill no)
			(layer "F.Fab")
		)
		(pad "1" smd custom
			(at 0 -0.4445 270)
			(size 0.1524 0.1524)
			(layers "F.Cu" "F.Mask" "F.Paste")
			(net "P1V8_E")
			(options
				(clearance outline)
				(anchor circle)
			)
			(primitives
				(gr_poly
					(pts
						(arc
							(start 0.3048 -0.2032)
							(mid 0.275042 -0.275042)
							(end 0.2032 -0.3048)
						)
						(arc
							(start -0.2032 -0.3048)
							(mid -0.275042 -0.275042)
							(end -0.3048 -0.2032)
						)
						(arc
							(start -0.3048 0.2032)
							(mid -0.275042 0.275042)
							(end -0.2032 0.3048)
						)
						(arc
							(start 0.2032 0.3048)
							(mid 0.275042 0.275042)
							(end 0.3048 0.2032)
						)
					)
					(width 0)
					(fill yes)
				)
			)
		)
		(pad "2" smd custom
			(at 0 0.4445 270)
			(size 0.1524 0.1524)
			(layers "F.Cu" "F.Mask" "F.Paste")
			(net "GND")
			(options
				(clearance outline)
				(anchor circle)
			)
			(primitives
				(gr_poly
					(pts
						(arc
							(start 0.3048 -0.2032)
							(mid 0.275042 -0.275042)
							(end 0.2032 -0.3048)
						)
						(arc
							(start -0.2032 -0.3048)
							(mid -0.275042 -0.275042)
							(end -0.3048 -0.2032)
						)
						(arc
							(start -0.3048 0.2032)
							(mid -0.275042 0.275042)
							(end -0.2032 0.3048)
						)
						(arc
							(start 0.2032 0.3048)
							(mid 0.275042 0.275042)
							(end 0.3048 0.2032)
						)
					)
					(width 0)
					(fill yes)
				)
			)
		)
	)
	(footprint ""
		(layer "F.Cu")
		(at 24.765 -237.236)
		(property "Reference" "SC426"
			(at 0 0 0)
			(layer "F.SilkS")
			(hide yes)
			(effects
				(font
					(size 1.27 1.27)
				)
			)
		)
		(property "Value" "SC1U10V3KX-4GP-U"
			(at 0 -2.8194 0)
			(unlocked yes)
			(layer "F.Fab")
			(hide yes)
			(effects
				(font
					(size 1.016 1.016)
					(thickness 0.1524)
				)
			)
		)
		(property "Device Type" "C603H36"
			(at 0 -4.3434 0)
			(unlocked yes)
			(layer "F.Fab")
			(hide yes)
			(effects
				(font
					(size 1.016 1.016)
					(thickness 0.1524)
				)
			)
		)
		(duplicate_pad_numbers_are_jumpers no)
		(fp_line
			(start 0.508 0)
			(end -0.508 0)
			(stroke
				(width 0.2032)
				(type default)
			)
			(layer "F.SilkS")
		)
		(fp_rect
			(start -0.5842 1.3335)
			(end 0.5842 -1.3335)
			(stroke
				(width 0)
				(type default)
			)
			(fill no)
			(layer "F.CrtYd")
		)
		(fp_rect
			(start -0.5842 1.3335)
			(end 0.5842 -1.3335)
			(stroke
				(width 0)
				(type default)
			)
			(fill no)
			(layer "F.Fab")
		)
		(pad "1" smd custom
			(at 0 -0.762)
			(size 0.2159 0.2159)
			(layers "F.Cu" "F.Mask" "F.Paste")
			(net "GND")
			(options
				(clearance outline)
				(anchor circle)
			)
			(primitives
				(gr_poly
					(pts
						(arc
							(start -0.3302 -0.4318)
							(mid -0.402042 -0.402042)
							(end -0.4318 -0.3302)
						)
						(arc
							(start -0.4318 0.3302)
							(mid -0.402042 0.402042)
							(end -0.3302 0.4318)
						)
						(arc
							(start 0.3302 0.4318)
							(mid 0.402042 0.402042)
							(end 0.4318 0.3302)
						)
						(arc
							(start 0.4318 -0.3302)
							(mid 0.402042 -0.402042)
							(end 0.3302 -0.4318)
						)
					)
					(width 0)
					(fill yes)
				)
			)
		)
		(pad "2" smd custom
			(at 0 0.762)
			(size 0.2159 0.2159)
			(layers "F.Cu" "F.Mask" "F.Paste")
			(net "P3V3_STBY")
			(options
				(clearance outline)
				(anchor circle)
			)
			(primitives
				(gr_poly
					(pts
						(arc
							(start -0.3302 -0.4318)
							(mid -0.402042 -0.402042)
							(end -0.4318 -0.3302)
						)
						(arc
							(start -0.4318 0.3302)
							(mid -0.402042 0.402042)
							(end -0.3302 0.4318)
						)
						(arc
							(start 0.3302 0.4318)
							(mid 0.402042 0.402042)
							(end 0.4318 0.3302)
						)
						(arc
							(start 0.4318 -0.3302)
							(mid 0.402042 -0.402042)
							(end 0.3302 -0.4318)
						)
					)
					(width 0)
					(fill yes)
				)
			)
		)
	)
)
